# TIMECARD (Time Appliance Project (Time Card)) — schematic netlist excerpt (pin names and nets, part order shuffled) for the footprints in the layout excerpt that follows; sources: Cadence DE-HDL packaged netlist, KiCad conversion of R4006-B0001-02_R01.brd

R1  RESISTOR  330OHM 1%  pkg SMC_0402R_H016  page 16 : \1\ = FPGA_OUT_SN_EEPROM_WP ; \2\ = SN_EEPROM_WP
R180  RESISTOR  1KOHM 1%  pkg SMC_0402R_H016  page 26 : \1\ = UNNAMED_14_OPTICAL_I142_A ; \2\ = XP5R0V
SP3  SOLDER_PREFORM  pkg 0201_SOLDER_PREFORM_4MIL  page 29 : \1\ = SG ; \2\ = XP1R0V_AGND

(kicad_pcb
	(version 20260206)
	(generator "pcbnew")
	(generator_version "10.0")
	(general
		(thickness 1.6)
		(legacy_teardrops no)
	)
	(paper "A4")
	(title_block
		(title "timecard-production-celestica-r4006 — R4006-B0001-02_R01.brd")
		(comment 1 "Time Appliance Project (Time Card) / footprints 1095-1097 of 1113")
	)
	(layers
		(0 "F.Cu" signal "TOP")
		(4 "In1.Cu" signal "L02_GND1")
		(6 "In2.Cu" signal "L03_SIG1")
		(8 "In3.Cu" signal "L04_GND2")
		(10 "In4.Cu" signal "L05_VCC1")
		(12 "In5.Cu" signal "L06_VCC2")
		(14 "In6.Cu" signal "L07_GND3")
		(16 "In7.Cu" signal "L08_SIG2")
		(18 "In8.Cu" signal "L09_GND4")
		(2 "B.Cu" signal "BOTTOM")
		(9 "F.Adhes" user "F.Adhesive")
		(11 "B.Adhes" user "B.Adhesive")
		(13 "F.Paste" user "Package Geometry/Pastemask Top")
		(15 "B.Paste" user "Package Geometry/Pastemask Bottom")
		(5 "F.SilkS" user "Ref Des/Silkscreen Top")
		(7 "B.SilkS" user "Ref Des/Silkscreen Bottom")
		(1 "F.Mask" user "Board Geometry/Soldermask Top")
		(3 "B.Mask" user "Board Geometry/Soldermask Bottom")
		(17 "Dwgs.User" user "User.Drawings")
		(19 "Cmts.User" user "User.Comments")
		(21 "Eco1.User" user "User.Eco1")
		(23 "Eco2.User" user "User.Eco2")
		(25 "Edge.Cuts" user "Board Geometry/Outline")
		(27 "Margin" user)
		(31 "F.CrtYd" user "Package Geometry/Place Bound Top")
		(29 "B.CrtYd" user "Package Geometry/Place Bound Bottom")
		(35 "F.Fab" user "Ref Des/Assembly Top")
		(33 "B.Fab" user "Ref Des/Assembly Bottom")
	)
	(footprint ""
		(layer "B.Cu")
		(at 30.34538 -17.99844)
		(property "Reference" "R1"
			(at 0.13462 -1.13919 0)
			(unlocked yes)
			(layer "B.SilkS")
			(effects
				(font
					(size 0.7874 0.5842)
					(thickness 0.1524)
				)
				(justify mirror)
			)
		)
		(property "Value" "VAL*"
			(at -0.02032 2.13233 0)
			(unlocked yes)
			(layer "B.Fab")
			(hide yes)
			(effects
				(font
					(size 0.7874 0.5842)
					(thickness 0.1524)
				)
				(justify mirror)
			)
		)
		(property "Device Type" "RESISTOR-G155-13300-01,330OHM,A"
			(at -0.008382 1.210564 0)
			(unlocked yes)
			(layer "B.Fab")
			(hide yes)
			(effects
				(font
					(size 0.7874 0.5842)
					(thickness 0.1524)
				)
				(justify mirror)
			)
		)
		(property "User Part Number" "PARTNUM*"
			(at -0.02032 4.024884 0)
			(unlocked yes)
			(layer "Cmts.User")
			(hide yes)
			(effects
				(font
					(size 0.7874 0.5842)
					(thickness 0.1524)
				)
				(justify mirror)
			)
		)
		(property "Tolerance" "TOL*"
			(at -0.044704 3.05435 0)
			(unlocked yes)
			(layer "Cmts.User")
			(hide yes)
			(effects
				(font
					(size 0.7874 0.5842)
					(thickness 0.1524)
				)
				(justify mirror)
			)
		)
		(duplicate_pad_numbers_are_jumpers no)
		(fp_line
			(start -1.143 -0.5588)
			(end 1.143 -0.5588)
			(stroke
				(width 0.1)
				(type default)
			)
			(layer "B.SilkS")
		)
		(fp_line
			(start -1.143 0.5588)
			(end -1.143 -0.5588)
			(stroke
				(width 0.1)
				(type default)
			)
			(layer "B.SilkS")
		)
		(fp_line
			(start 1.143 -0.5588)
			(end 1.143 0.5588)
			(stroke
				(width 0.1)
				(type default)
			)
			(layer "B.SilkS")
		)
		(fp_line
			(start 1.143 0.5588)
			(end -1.143 0.5588)
			(stroke
				(width 0.1)
				(type default)
			)
			(layer "B.SilkS")
		)
		(fp_rect
			(start 1.143 0.5588)
			(end -1.143 -0.5588)
			(stroke
				(width 0)
				(type default)
			)
			(fill no)
			(layer "B.CrtYd")
		)
		(fp_line
			(start -0.508 -0.3048)
			(end 0.508 -0.3048)
			(stroke
				(width 0.1)
				(type default)
			)
			(layer "B.Fab")
		)
		(fp_line
			(start -0.508 0.3048)
			(end -0.508 -0.3048)
			(stroke
				(width 0.1)
				(type default)
			)
			(layer "B.Fab")
		)
		(fp_line
			(start 0.508 -0.3048)
			(end 0.508 0.3048)
			(stroke
				(width 0.1)
				(type default)
			)
			(layer "B.Fab")
		)
		(fp_line
			(start 0.508 0.3048)
			(end -0.508 0.3048)
			(stroke
				(width 0.1)
				(type default)
			)
			(layer "B.Fab")
		)
		(pad "1" smd rect
			(at 0.5334 0 180)
			(size 0.7112 0.6096)
			(layers "B.Cu" "B.Mask" "B.Paste")
			(net "FPGA_OUT_SN_EEPROM_WP")
		)
		(pad "2" smd rect
			(at -0.5334 0 180)
			(size 0.7112 0.6096)
			(layers "B.Cu" "B.Mask" "B.Paste")
			(net "SN_EEPROM_WP")
		)
		(zone
			(layer "B.Cu")
			(hatch none 0.5)
			(connect_pads
				(clearance 0)
			)
			(min_thickness 0.25)
			(keepout
				(tracks allowed)
				(vias not_allowed)
				(pads allowed)
				(copperpour not_allowed)
				(footprints allowed)
			)
			(placement
				(enabled no)
				(sheetname "")
			)
			(fill
				(thermal_gap 0.5)
				(thermal_bridge_width 0.5)
				(island_removal_mode 0)
			)
			(polygon
				(pts
					(xy 30.42158 -17.69364) (xy 30.42158 -18.30324) (xy 30.26918 -18.30324) (xy 30.26918 -17.69364)
				)
			)
		)
	)
	(footprint ""
		(layer "B.Cu")
		(at 144.145 -104.267 90)
		(property "Reference" "R180"
			(at -1.143 0.98425 270)
			(unlocked yes)
			(layer "B.SilkS")
			(effects
				(font
					(size 0.635 0.4064)
					(thickness 0.1524)
				)
				(justify mirror)
			)
		)
		(property "Value" "VAL*"
			(at -0.02032 2.13233 90)
			(unlocked yes)
			(layer "B.Fab")
			(hide yes)
			(effects
				(font
					(size 0.7874 0.5842)
					(thickness 0.1524)
				)
				(justify mirror)
			)
		)
		(property "Tolerance" "TOL*"
			(at -0.044704 3.05435 90)
			(unlocked yes)
			(layer "Cmts.User")
			(hide yes)
			(effects
				(font
					(size 0.7874 0.5842)
					(thickness 0.1524)
				)
				(justify mirror)
			)
		)
		(property "User Part Number" "PARTNUM*"
			(at -0.02032 4.024884 90)
			(unlocked yes)
			(layer "Cmts.User")
			(hide yes)
			(effects
				(font
					(size 0.7874 0.5842)
					(thickness 0.1524)
				)
				(justify mirror)
			)
		)
		(property "Device Type" "RESISTOR-G155-11001-01,1KOHM,1%"
			(at -0.008382 1.210564 90)
			(unlocked yes)
			(layer "B.Fab")
			(hide yes)
			(effects
				(font
					(size 0.7874 0.5842)
					(thickness 0.1524)
				)
				(justify mirror)
			)
		)
		(duplicate_pad_numbers_are_jumpers no)
		(fp_line
			(start 1.143 -0.5588)
			(end 1.143 0.5588)
			(stroke
				(width 0.1)
				(type default)
			)
			(layer "B.SilkS")
		)
		(fp_line
			(start -1.143 -0.5588)
			(end 1.143 -0.5588)
			(stroke
				(width 0.1)
				(type default)
			)
			(layer "B.SilkS")
		)
		(fp_line
			(start 1.143 0.5588)
			(end -1.143 0.5588)
			(stroke
				(width 0.1)
				(type default)
			)
			(layer "B.SilkS")
		)
		(fp_line
			(start -1.143 0.5588)
			(end -1.143 -0.5588)
			(stroke
				(width 0.1)
				(type default)
			)
			(layer "B.SilkS")
		)
		(fp_rect
			(start -1.143 -0.5588)
			(end 1.143 0.5588)
			(stroke
				(width 0)
				(type default)
			)
			(fill no)
			(layer "B.CrtYd")
		)
		(fp_line
			(start 0.508 -0.3048)
			(end 0.508 0.3048)
			(stroke
				(width 0.1)
				(type default)
			)
			(layer "B.Fab")
		)
		(fp_line
			(start -0.508 -0.3048)
			(end 0.508 -0.3048)
			(stroke
				(width 0.1)
				(type default)
			)
			(layer "B.Fab")
		)
		(fp_line
			(start 0.508 0.3048)
			(end -0.508 0.3048)
			(stroke
				(width 0.1)
				(type default)
			)
			(layer "B.Fab")
		)
		(fp_line
			(start -0.508 0.3048)
			(end -0.508 -0.3048)
			(stroke
				(width 0.1)
				(type default)
			)
			(layer "B.Fab")
		)
		(pad "1" smd rect
			(at 0.5334 0 270)
			(size 0.7112 0.6096)
			(layers "B.Cu" "B.Mask" "B.Paste")
			(net "UNNAMED_14_OPTICAL_I142_A")
		)
		(pad "2" smd rect
			(at -0.5334 0 270)
			(size 0.7112 0.6096)
			(layers "B.Cu" "B.Mask" "B.Paste")
			(net "XP5R0V")
		)
		(zone
			(layer "B.Cu")
			(hatch none 0.5)
			(connect_pads
				(clearance 0)
			)
			(min_thickness 0.25)
			(keepout
				(tracks allowed)
				(vias not_allowed)
				(pads allowed)
				(copperpour not_allowed)
				(footprints allowed)
			)
			(placement
				(enabled no)
				(sheetname "")
			)
			(fill
				(thermal_gap 0.5)
				(thermal_bridge_width 0.5)
				(island_removal_mode 0)
			)
			(polygon
				(pts
					(xy 143.8402 -104.1908) (xy 144.4498 -104.1908) (xy 144.4498 -104.3432) (xy 143.8402 -104.3432)
				)
			)
		)
	)
	(footprint ""
		(layer "B.Cu")
		(at 143.256 -55.118 -90)
		(property "Reference" "SP3"
			(at 1.81737 -0.254 0)
			(unlocked yes)
			(layer "B.SilkS")
			(effects
				(font
					(size 0.7874 0.5842)
					(thickness 0.1524)
				)
				(justify mirror)
			)
		)
		(property "Value" ""
			(at 0 0 90)
			(layer "B.Fab")
			(effects
				(font
					(size 1.27 1.27)
				)
				(justify mirror)
			)
		)
		(duplicate_pad_numbers_are_jumpers no)
		(fp_rect
			(start 0.1778 0.3048)
			(end -0.1778 -0.3048)
			(stroke
				(width 0)
				(type default)
			)
			(fill yes)
			(layer "B.Paste")
		)
		(fp_rect
			(start 0.2286 0.3556)
			(end -0.2286 -0.3556)
			(stroke
				(width 0)
				(type default)
			)
			(fill no)
			(layer "B.CrtYd")
		)
		(fp_line
			(start -0.1397 0.2413)
			(end 0.1397 0.2413)
			(stroke
				(width 0.1)
				(type default)
			)
			(layer "B.Fab")
		)
		(fp_line
			(start 0.1397 0.2413)
			(end 0.1397 -0.2413)
			(stroke
				(width 0.1)
				(type default)
			)
			(layer "B.Fab")
		)
		(fp_line
			(start -0.1397 -0.2413)
			(end -0.1397 0.2413)
			(stroke
				(width 0.1)
				(type default)
			)
			(layer "B.Fab")
		)
		(fp_line
			(start 0.1397 -0.2413)
			(end -0.1397 -0.2413)
			(stroke
				(width 0.1)
				(type default)
			)
			(layer "B.Fab")
		)
		(pad "1" smd rect
			(at 0.1143 0 90)
			(size 0.127 0.6096)
			(layers "B.Cu" "B.Mask" "B.Paste")
			(net "SG")
		)
		(pad "2" smd rect
			(at -0.1143 0 90)
			(size 0.127 0.6096)
			(layers "B.Cu" "B.Mask" "B.Paste")
			(net "XP1R0V_AGND")
		)
	)
)
